(kicad_pcb
	(version 20260206)
	(generator "pcbnew")
	(generator_version "10.0")
	(general
		(thickness 1.6)
		(legacy_teardrops no)
	)
	(paper "A4")
	(title_block
		(title "fcb — 12433-1M.1206WZS1330.brd")
		(comment 1 "Open Vault / Knox (Wiwynn) / footprints 110-115 of 495")
	)
	(layers
		(0 "F.Cu" signal "TOP")
		(4 "In1.Cu" signal "L2GND")
		(6 "In2.Cu" signal "L3VCC")
		(2 "B.Cu" signal "BOTTOM")
		(9 "F.Adhes" user "F.Adhesive")
		(11 "B.Adhes" user "B.Adhesive")
		(13 "F.Paste" user "Package Geometry/Pastemask Top")
		(15 "B.Paste" user "Package Geometry/Pastemask Bottom")
		(5 "F.SilkS" user "Ref Des/Silkscreen Top")
		(7 "B.SilkS" user "Ref Des/Silkscreen Bottom")
		(1 "F.Mask" user "Board Geometry/Soldermask Top")
		(3 "B.Mask" user "Board Geometry/Soldermask Bottom")
		(17 "Dwgs.User" user "User.Drawings")
		(19 "Cmts.User" user "User.Comments")
		(21 "Eco1.User" user "User.Eco1")
		(23 "Eco2.User" user "User.Eco2")
		(25 "Edge.Cuts" user "Board Geometry/Outline")
		(27 "Margin" user)
		(31 "F.CrtYd" user "Package Geometry/Place Bound Top")
		(29 "B.CrtYd" user "Package Geometry/Place Bound Bottom")
		(35 "F.Fab" user "Ref Des/Assembly Top")
		(33 "B.Fab" user "Ref Des/Assembly Bottom")
	)
	(footprint ""
		(layer "F.Cu")
		(at 43.7134 -138.5062)
		(property "Reference" "PC95"
			(at 0 0 0)
			(layer "F.SilkS")
			(hide yes)
			(effects
				(font
					(size 1.27 1.27)
				)
			)
		)
		(property "Value" "SC10U25V5KX-GP"
			(at -0.0762 -6.1214 0)
			(unlocked yes)
			(layer "F.Fab")
			(hide yes)
			(effects
				(font
					(size 1.016 1.016)
					(thickness 0.1524)
				)
			)
		)
		(property "Device Type" "C805H56"
			(at -0.0762 -8.1534 0)
			(unlocked yes)
			(layer "F.Fab")
			(hide yes)
			(effects
				(font
					(size 1.016 1.016)
					(thickness 0.1524)
				)
			)
		)
		(duplicate_pad_numbers_are_jumpers no)
		(fp_line
			(start 0.635 0)
			(end -0.635 0)
			(stroke
				(width 0.508)
				(type default)
			)
			(layer "F.SilkS")
		)
		(fp_rect
			(start -0.9652 1.778)
			(end 0.9652 -1.778)
			(stroke
				(width 0)
				(type default)
			)
			(fill no)
			(layer "F.CrtYd")
		)
		(fp_poly
			(pts
				(xy -0.9652 -1.778) (xy 0.9652 -1.778) (xy 0.9652 1.778) (xy -0.9652 1.778)
			)
			(stroke
				(width 0)
				(type default)
			)
			(fill no)
			(layer "F.Fab")
		)
		(pad "1" smd rect
			(at 0 -0.9652)
			(size 1.397 1.143)
			(layers "F.Cu" "F.Mask" "F.Paste")
			(net "P12VL_2490_EN_2")
		)
		(pad "2" smd rect
			(at 0 0.9652)
			(size 1.397 1.143)
			(layers "F.Cu" "F.Mask" "F.Paste")
			(net "GND")
		)
	)
	(footprint ""
		(layer "F.Cu")
		(at 26.4922 -251.6632 -90)
		(property "Reference" "C13"
			(at 0 0 270)
			(layer "F.SilkS")
			(hide yes)
			(effects
				(font
					(size 1.27 1.27)
				)
			)
		)
		(property "Value" "SC1U16V3KX-5GP"
			(at 0 -2.8194 270)
			(unlocked yes)
			(layer "F.Fab")
			(hide yes)
			(effects
				(font
					(size 1.016 1.016)
					(thickness 0.1524)
				)
			)
		)
		(property "Device Type" "C603H36"
			(at 0 -4.3434 270)
			(unlocked yes)
			(layer "F.Fab")
			(hide yes)
			(effects
				(font
					(size 1.016 1.016)
					(thickness 0.1524)
				)
			)
		)
		(duplicate_pad_numbers_are_jumpers no)
		(fp_line
			(start 0.508 0)
			(end -0.508 0)
			(stroke
				(width 0.2032)
				(type default)
			)
			(layer "F.SilkS")
		)
		(fp_rect
			(start -0.5842 1.3335)
			(end 0.5842 -1.3335)
			(stroke
				(width 0)
				(type default)
			)
			(fill no)
			(layer "F.CrtYd")
		)
		(fp_rect
			(start -0.5842 1.3335)
			(end 0.5842 -1.3335)
			(stroke
				(width 0)
				(type default)
			)
			(fill no)
			(layer "F.Fab")
		)
		(pad "1" smd custom
			(at 0 -0.762 270)
			(size 0.2159 0.2159)
			(layers "F.Cu" "F.Mask" "F.Paste")
			(net "P3V3")
			(options
				(clearance outline)
				(anchor circle)
			)
			(primitives
				(gr_poly
					(pts
						(arc
							(start -0.3302 -0.4318)
							(mid -0.402042 -0.402042)
							(end -0.4318 -0.3302)
						)
						(arc
							(start -0.4318 0.3302)
							(mid -0.402042 0.402042)
							(end -0.3302 0.4318)
						)
						(arc
							(start 0.3302 0.4318)
							(mid 0.402042 0.402042)
							(end 0.4318 0.3302)
						)
						(arc
							(start 0.4318 -0.3302)
							(mid 0.402042 -0.402042)
							(end 0.3302 -0.4318)
						)
					)
					(width 0)
					(fill yes)
				)
			)
		)
		(pad "2" smd custom
			(at 0 0.762 270)
			(size 0.2159 0.2159)
			(layers "F.Cu" "F.Mask" "F.Paste")
			(net "GND")
			(options
				(clearance outline)
				(anchor circle)
			)
			(primitives
				(gr_poly
					(pts
						(arc
							(start -0.3302 -0.4318)
							(mid -0.402042 -0.402042)
							(end -0.4318 -0.3302)
						)
						(arc
							(start -0.4318 0.3302)
							(mid -0.402042 0.402042)
							(end -0.3302 0.4318)
						)
						(arc
							(start 0.3302 0.4318)
							(mid 0.402042 0.402042)
							(end 0.4318 0.3302)
						)
						(arc
							(start 0.4318 -0.3302)
							(mid 0.402042 -0.402042)
							(end 0.3302 -0.4318)
						)
					)
					(width 0)
					(fill yes)
				)
			)
		)
	)
	(footprint ""
		(layer "F.Cu")
		(at 8.9662 -106.2482 -90)
		(property "Reference" "TC2"
			(at 0 0 270)
			(layer "F.SilkS")
			(hide yes)
			(effects
				(font
					(size 1.27 1.27)
				)
			)
		)
		(property "Value" "ST68U16VDM-1-GP"
			(at 0 -9.6012 270)
			(unlocked yes)
			(layer "F.Fab")
			(hide yes)
			(effects
				(font
					(size 1.016 1.016)
					(thickness 0.1524)
				)
			)
		)
		(property "Device Type" "CT7343H79"
			(at 0 -11.1252 270)
			(unlocked yes)
			(layer "F.Fab")
			(hide yes)
			(effects
				(font
					(size 1.016 1.016)
					(thickness 0.1524)
				)
			)
		)
		(duplicate_pad_numbers_are_jumpers no)
		(fp_line
			(start -2.286 4.8768)
			(end -2.286 2.032)
			(stroke
				(width 0.1524)
				(type default)
			)
			(layer "F.SilkS")
		)
		(fp_line
			(start 2.286 4.8768)
			(end -2.286 4.8768)
			(stroke
				(width 0.1524)
				(type default)
			)
			(layer "F.SilkS")
		)
		(fp_line
			(start 2.286 2.032)
			(end 2.286 4.8768)
			(stroke
				(width 0.1524)
				(type default)
			)
			(layer "F.SilkS")
		)
		(fp_line
			(start 2.286 -2.032)
			(end 2.286 -4.8768)
			(stroke
				(width 0.1524)
				(type default)
			)
			(layer "F.SilkS")
		)
		(fp_line
			(start 2.1082 -4.699)
			(end -2.1082 -4.699)
			(stroke
				(width 0.508)
				(type default)
			)
			(layer "F.SilkS")
		)
		(fp_line
			(start -2.286 -4.8768)
			(end -2.286 -2.032)
			(stroke
				(width 0.1524)
				(type default)
			)
			(layer "F.SilkS")
		)
		(fp_line
			(start 2.286 -4.8768)
			(end -2.286 -4.8768)
			(stroke
				(width 0.1524)
				(type default)
			)
			(layer "F.SilkS")
		)
		(fp_rect
			(start -2.1463 3.6449)
			(end 2.1463 -3.6449)
			(stroke
				(width 0)
				(type default)
			)
			(fill no)
			(layer "F.CrtYd")
		)
		(fp_poly
			(pts
				(xy -2.54 4.953) (xy -2.54 4.2926) (xy -3.81 4.2926) (xy -3.81 -4.2926) (xy -2.54 -4.2926) (xy -2.54 -4.953)
				(xy 2.54 -4.953) (xy 2.54 -4.2926) (xy 3.81 -4.2926) (xy 3.81 -1.6256) (xy 2.1463 -1.6256) (xy 2.1463 -3.6449)
				(xy -2.1463 -3.6449) (xy -2.1463 3.6449) (xy 2.1463 3.6449) (xy 2.1463 -1.6129) (xy 3.81 -1.6129)
				(xy 3.81 4.2926) (xy 2.54 4.2926) (xy 2.54 4.953)
			)
			(stroke
				(width 0)
				(type default)
			)
			(fill no)
			(layer "F.CrtYd")
		)
		(fp_rect
			(start -2.54 4.953)
			(end 2.54 -4.953)
			(stroke
				(width 0)
				(type default)
			)
			(fill no)
			(layer "F.Fab")
		)
		(fp_rect
			(start -3.81 4.2926)
			(end -2.54 -4.2926)
			(stroke
				(width 0)
				(type default)
			)
			(fill no)
			(layer "F.Fab")
		)
		(fp_rect
			(start 2.54 4.2926)
			(end 3.81 -4.2926)
			(stroke
				(width 0)
				(type default)
			)
			(fill no)
			(layer "F.Fab")
		)
		(pad "1" smd rect
			(at 0 -3.1496 270)
			(size 2.413 2.286)
			(layers "F.Cu" "F.Mask" "F.Paste")
			(net "P12VU")
		)
		(pad "2" smd rect
			(at 0 3.1496 270)
			(size 2.413 2.286)
			(layers "F.Cu" "F.Mask" "F.Paste")
			(net "GND")
		)
		(zone
			(layer "F.Cu")
			(hatch none 0.5)
			(connect_pads
				(clearance 0)
			)
			(min_thickness 0.25)
			(keepout
				(tracks allowed)
				(vias not_allowed)
				(pads allowed)
				(copperpour not_allowed)
				(footprints allowed)
			)
			(placement
				(enabled no)
				(sheetname "")
			)
			(fill
				(thermal_gap 0.5)
				(thermal_bridge_width 0.5)
				(island_removal_mode 0)
			)
			(polygon
				(pts
					(xy 4.3688 -107.7595) (xy 4.3688 -104.7369) (xy 7.2644 -104.7369) (xy 7.5946 -104.7369) (xy 7.5946 -107.7595)
					(xy 7.2644 -107.7595)
				)
			)
		)
		(zone
			(layer "F.Cu")
			(hatch none 0.5)
			(connect_pads
				(clearance 0)
			)
			(min_thickness 0.25)
			(keepout
				(tracks allowed)
				(vias not_allowed)
				(pads allowed)
				(copperpour not_allowed)
				(footprints allowed)
			)
			(placement
				(enabled no)
				(sheetname "")
			)
			(fill
				(thermal_gap 0.5)
				(thermal_bridge_width 0.5)
				(island_removal_mode 0)
			)
			(polygon
				(pts
					(xy 10.6553 -104.7369) (xy 13.5636 -104.7369) (xy 13.5636 -107.7595) (xy 10.668 -107.7595) (xy 10.3378 -107.7595)
					(xy 10.3378 -104.7369)
				)
			)
		)
	)
	(footprint ""
		(layer "F.Cu")
		(at 30.904434 -238.266224 180)
		(property "Reference" "R41"
			(at 0 0 180)
			(layer "F.SilkS")
			(hide yes)
			(effects
				(font
					(size 1.27 1.27)
				)
			)
		)
		(property "Value" "4K7R2J-2-GP"
			(at 0.064008 -3.993896 180)
			(unlocked yes)
			(layer "F.Fab")
			(hide yes)
			(effects
				(font
					(size 1.016 1.016)
					(thickness 0.1524)
				)
			)
		)
		(property "Device Type" "R402H16"
			(at 0.064008 -5.517896 180)
			(unlocked yes)
			(layer "F.Fab")
			(hide yes)
			(effects
				(font
					(size 1.016 1.016)
					(thickness 0.1524)
				)
			)
		)
		(duplicate_pad_numbers_are_jumpers no)
		(fp_line
			(start 0.508 -0.9398)
			(end -0.508 -0.9398)
			(stroke
				(width 0.1524)
				(type default)
			)
			(layer "F.SilkS")
		)
		(fp_line
			(start -0.508 -0.9398)
			(end -0.508 0.9398)
			(stroke
				(width 0.1524)
				(type default)
			)
			(layer "F.SilkS")
		)
		(fp_rect
			(start -0.508 0.9398)
			(end 0.508 -0.9398)
			(stroke
				(width 0)
				(type default)
			)
			(fill no)
			(layer "F.CrtYd")
		)
		(fp_rect
			(start -0.508 0.9398)
			(end 0.508 -0.9398)
			(stroke
				(width 0)
				(type default)
			)
			(fill no)
			(layer "F.Fab")
		)
		(pad "1" smd custom
			(at 0 -0.4445 180)
			(size 0.1397 0.1397)
			(layers "F.Cu" "F.Mask" "F.Paste")
			(net "P3V3")
			(options
				(clearance outline)
				(anchor circle)
			)
			(primitives
				(gr_poly
					(pts
						(arc
							(start -0.1778 -0.2794)
							(mid -0.249642 -0.249642)
							(end -0.2794 -0.1778)
						)
						(arc
							(start -0.2794 0.1778)
							(mid -0.249642 0.249642)
							(end -0.1778 0.2794)
						)
						(arc
							(start 0.1778 0.2794)
							(mid 0.249642 0.249642)
							(end 0.2794 0.1778)
						)
						(arc
							(start 0.2794 -0.1778)
							(mid 0.249642 -0.249642)
							(end 0.1778 -0.2794)
						)
					)
					(width 0)
					(fill yes)
				)
			)
		)
		(pad "2" smd custom
			(at 0 0.4445 180)
			(size 0.1397 0.1397)
			(layers "F.Cu" "F.Mask" "F.Paste")
			(net "FCB_EEPROM_A2")
			(options
				(clearance outline)
				(anchor circle)
			)
			(primitives
				(gr_poly
					(pts
						(arc
							(start -0.1778 -0.2794)
							(mid -0.249642 -0.249642)
							(end -0.2794 -0.1778)
						)
						(arc
							(start -0.2794 0.1778)
							(mid -0.249642 0.249642)
							(end -0.1778 0.2794)
						)
						(arc
							(start 0.1778 0.2794)
							(mid 0.249642 0.249642)
							(end 0.2794 0.1778)
						)
						(arc
							(start 0.2794 -0.1778)
							(mid 0.249642 -0.249642)
							(end 0.1778 -0.2794)
						)
					)
					(width 0)
					(fill yes)
				)
			)
		)
	)
	(footprint ""
		(layer "F.Cu")
		(at 19.558 -185.1914 180)
		(property "Reference" "R89"
			(at 0 0 180)
			(layer "F.SilkS")
			(hide yes)
			(effects
				(font
					(size 1.27 1.27)
				)
			)
		)
		(property "Value" "10KR2F-2-GP"
			(at 0.064008 -3.993896 180)
			(unlocked yes)
			(layer "F.Fab")
			(hide yes)
			(effects
				(font
					(size 1.016 1.016)
					(thickness 0.1524)
				)
			)
		)
		(property "Device Type" "R402H16"
			(at 0.064008 -5.517896 180)
			(unlocked yes)
			(layer "F.Fab")
			(hide yes)
			(effects
				(font
					(size 1.016 1.016)
					(thickness 0.1524)
				)
			)
		)
		(duplicate_pad_numbers_are_jumpers no)
		(fp_line
			(start 0.508 -0.9398)
			(end -0.508 -0.9398)
			(stroke
				(width 0.1524)
				(type default)
			)
			(layer "F.SilkS")
		)
		(fp_line
			(start -0.508 -0.9398)
			(end -0.508 0.9398)
			(stroke
				(width 0.1524)
				(type default)
			)
			(layer "F.SilkS")
		)
		(fp_rect
			(start -0.508 0.9398)
			(end 0.508 -0.9398)
			(stroke
				(width 0)
				(type default)
			)
			(fill no)
			(layer "F.CrtYd")
		)
		(fp_rect
			(start -0.508 0.9398)
			(end 0.508 -0.9398)
			(stroke
				(width 0)
				(type default)
			)
			(fill no)
			(layer "F.Fab")
		)
		(pad "1" smd custom
			(at 0 -0.4445 180)
			(size 0.1397 0.1397)
			(layers "F.Cu" "F.Mask" "F.Paste")
			(net "FANIN_8")
			(options
				(clearance outline)
				(anchor circle)
			)
			(primitives
				(gr_poly
					(pts
						(arc
							(start -0.1778 -0.2794)
							(mid -0.249642 -0.249642)
							(end -0.2794 -0.1778)
						)
						(arc
							(start -0.2794 0.1778)
							(mid -0.249642 0.249642)
							(end -0.1778 0.2794)
						)
						(arc
							(start 0.1778 0.2794)
							(mid 0.249642 0.249642)
							(end 0.2794 0.1778)
						)
						(arc
							(start 0.2794 -0.1778)
							(mid 0.249642 -0.249642)
							(end 0.1778 -0.2794)
						)
					)
					(width 0)
					(fill yes)
				)
			)
		)
		(pad "2" smd custom
			(at 0 0.4445 180)
			(size 0.1397 0.1397)
			(layers "F.Cu" "F.Mask" "F.Paste")
			(net "GND")
			(options
				(clearance outline)
				(anchor circle)
			)
			(primitives
				(gr_poly
					(pts
						(arc
							(start -0.1778 -0.2794)
							(mid -0.249642 -0.249642)
							(end -0.2794 -0.1778)
						)
						(arc
							(start -0.2794 0.1778)
							(mid -0.249642 0.249642)
							(end -0.1778 0.2794)
						)
						(arc
							(start 0.1778 0.2794)
							(mid 0.249642 0.249642)
							(end 0.2794 0.1778)
						)
						(arc
							(start 0.2794 -0.1778)
							(mid 0.249642 -0.249642)
							(end 0.1778 -0.2794)
						)
					)
					(width 0)
					(fill yes)
				)
			)
		)
	)
	(footprint ""
		(layer "F.Cu")
		(at 41.4274 -135.1534 -90)
		(property "Reference" "PR100"
			(at 0 0 270)
			(layer "F.SilkS")
			(hide yes)
			(effects
				(font
					(size 1.27 1.27)
				)
			)
		)
		(property "Value" "1MR3J-L-GP"
			(at -0.0254 -2.5146 270)
			(unlocked yes)
			(layer "F.Fab")
			(hide yes)
			(effects
				(font
					(size 1.016 1.016)
					(thickness 0.1524)
				)
			)
		)
		(property "Device Type" "R603H22"
			(at -0.0254 -4.0386 270)
			(unlocked yes)
			(layer "F.Fab")
			(hide yes)
			(effects
				(font
					(size 1.016 1.016)
					(thickness 0.1524)
				)
			)
		)
		(duplicate_pad_numbers_are_jumpers no)
		(fp_line
			(start -0.4826 0)
			(end -0.2032 0)
			(stroke
				(width 0.2032)
				(type default)
			)
			(layer "F.SilkS")
		)
		(fp_line
			(start 0.2032 0)
			(end 0.4826 0)
			(stroke
				(width 0.2032)
				(type default)
			)
			(layer "F.SilkS")
		)
		(fp_rect
			(start -0.5842 1.3335)
			(end 0.5842 -1.3335)
			(stroke
				(width 0)
				(type default)
			)
			(fill no)
			(layer "F.CrtYd")
		)
		(fp_rect
			(start -0.5842 1.3335)
			(end 0.5842 -1.3335)
			(stroke
				(width 0)
				(type default)
			)
			(fill no)
			(layer "F.Fab")
		)
		(pad "1" smd custom
			(at 0 -0.762 270)
			(size 0.2159 0.2159)
			(layers "F.Cu" "F.Mask" "F.Paste")
			(net "P12VL_2490_VCC")
			(options
				(clearance outline)
				(anchor circle)
			)
			(primitives
				(gr_poly
					(pts
						(arc
							(start -0.3302 -0.4318)
							(mid -0.402042 -0.402042)
							(end -0.4318 -0.3302)
						)
						(arc
							(start -0.4318 0.3302)
							(mid -0.402042 0.402042)
							(end -0.3302 0.4318)
						)
						(arc
							(start 0.3302 0.4318)
							(mid 0.402042 0.402042)
							(end 0.4318 0.3302)
						)
						(arc
							(start 0.4318 -0.3302)
							(mid 0.402042 -0.402042)
							(end 0.3302 -0.4318)
						)
					)
					(width 0)
					(fill yes)
				)
			)
		)
		(pad "2" smd custom
			(at 0 0.762 270)
			(size 0.2159 0.2159)
			(layers "F.Cu" "F.Mask" "F.Paste")
			(net "P12VL_2490_SENSE")
			(options
				(clearance outline)
				(anchor circle)
			)
			(primitives
				(gr_poly
					(pts
						(arc
							(start -0.3302 -0.4318)
							(mid -0.402042 -0.402042)
							(end -0.4318 -0.3302)
						)
						(arc
							(start -0.4318 0.3302)
							(mid -0.402042 0.402042)
							(end -0.3302 0.4318)
						)
						(arc
							(start 0.3302 0.4318)
							(mid 0.402042 0.402042)
							(end 0.4318 0.3302)
						)
						(arc
							(start 0.4318 -0.3302)
							(mid 0.402042 -0.402042)
							(end 0.3302 -0.4318)
						)
					)
					(width 0)
					(fill yes)
				)
			)
		)
	)
)
